(kicad_pcb
	(version 20240108)
	(generator "pcbnew")
	(generator_version "8.0")
	(general
		(thickness 1.62)
		(legacy_teardrops no)
	)
	(paper "A4")
	(title_block
		(title "Jetson Orin Baseboard")
		(date "2025-03-12")
		(rev "1.3.4")
		(company "Antmicro Ltd")
		(comment 1 "www.antmicro.com")
		(comment 9 "footprints 132-136 of 677")
	)
	(layers
		(0 "F.Cu" signal)
		(1 "In1.Cu" signal)
		(2 "In2.Cu" signal)
		(3 "In3.Cu" signal)
		(4 "In4.Cu" jumper)
		(5 "In5.Cu" signal)
		(6 "In6.Cu" signal)
		(31 "B.Cu" signal)
		(32 "B.Adhes" user "B.Adhesive")
		(33 "F.Adhes" user "F.Adhesive")
		(34 "B.Paste" user)
		(35 "F.Paste" user)
		(36 "B.SilkS" user "B.Silkscreen")
		(37 "F.SilkS" user "F.Silkscreen")
		(38 "B.Mask" user)
		(39 "F.Mask" user)
		(40 "Dwgs.User" user "User.Drawings")
		(41 "Cmts.User" user "User.Comments")
		(42 "Eco1.User" user "User.Eco1")
		(43 "Eco2.User" user "User.Eco2")
		(44 "Edge.Cuts" user)
		(45 "Margin" user)
		(46 "B.CrtYd" user "B.Courtyard")
		(47 "F.CrtYd" user "F.Courtyard")
		(48 "B.Fab" user)
		(49 "F.Fab" user)
	)
	(footprint "antmicro-footprints:USON-10_2.5x1mm_P0.5mm"
		(layer "F.Cu")
		(at 96.675 119.9 90)
		(descr "USON-10 2.5x1mm_ Pitch 0.5mm")
		(tags "USON-10 2.5x1mm Pitch 0.5mm")
		(property "Reference" "U44"
			(at -0.1 3.325 -90)
			(layer "F.SilkS")
			(effects
				(font
					(size 0.7 0.7)
					(thickness 0.15)
				)
				(justify left bottom)
			)
		)
		(property "Value" "TPD4E05U06QDQARQ1"
			(at 0.018 2.499 90)
			(layer "F.Fab")
			(effects
				(font
					(size 0.7 0.7)
					(thickness 0.15)
				)
				(justify left bottom)
			)
		)
		(property "Footprint" "antmicro-footprints:USON-10_2.5x1mm_P0.5mm"
			(at 0 0 90)
			(layer "F.Fab")
			(hide yes)
			(effects
				(font
					(size 1.27 1.27)
					(thickness 0.15)
				)
			)
		)
		(property "Datasheet" "https://www.ti.com/lit/ds/symlink/tpd4e05u06-q1.pdf?HQS=dis-mous-null-mousermode-dsf-pf-null-wwe&ts=1663591265741&ref_url=https%253A%252F%252Fwww.mouser.com%252F"
			(at 0 0 90)
			(layer "F.Fab")
			(hide yes)
			(effects
				(font
					(size 1.27 1.27)
					(thickness 0.15)
				)
			)
		)
		(property "Author" "Antmicro"
			(at 216.575 23.225 0)
			(layer "F.Fab")
			(hide yes)
			(effects
				(font
					(size 1 1)
					(thickness 0.15)
				)
			)
		)
		(property "License" "Apache-2.0"
			(at 216.575 23.225 0)
			(layer "F.Fab")
			(hide yes)
			(effects
				(font
					(size 1 1)
					(thickness 0.15)
				)
			)
		)
		(property "MPN" "TPD4E05U06QDQARQ1"
			(at 216.575 23.225 0)
			(layer "F.Fab")
			(hide yes)
			(effects
				(font
					(size 1 1)
					(thickness 0.15)
				)
			)
		)
		(property "Manufacturer" "Texas Instruments"
			(at 216.575 23.225 0)
			(layer "F.Fab")
			(hide yes)
			(effects
				(font
					(size 1 1)
					(thickness 0.15)
				)
			)
		)
		(sheetname "HDMI")
		(sheetfile "hdmi.kicad_sch")
		(attr smd)
		(fp_line
			(start 0.498 -1.401)
			(end -0.5 -1.401)
			(stroke
				(width 0.15)
				(type solid)
			)
			(layer "F.SilkS")
		)
		(fp_line
			(start 0.498 1.398)
			(end -0.5 1.398)
			(stroke
				(width 0.15)
				(type solid)
			)
			(layer "F.SilkS")
		)
		(fp_circle
			(center -0.68 -1.27)
			(end -0.63 -1.27)
			(stroke
				(width 0.15)
				(type solid)
			)
			(fill solid)
			(layer "F.SilkS")
		)
		(fp_rect
			(start -0.8 -1.5)
			(end 0.8 1.499)
			(stroke
				(width 0.05)
				(type solid)
			)
			(fill none)
			(layer "F.CrtYd")
		)
		(fp_line
			(start 0.498 -1.25)
			(end -0.25 -1.25)
			(stroke
				(width 0.15)
				(type solid)
			)
			(layer "F.Fab")
		)
		(fp_line
			(start 0.498 -1.25)
			(end 0.498 1.249)
			(stroke
				(width 0.15)
				(type solid)
			)
			(layer "F.Fab")
		)
		(fp_line
			(start -0.25 -1.25)
			(end -0.5 -1)
			(stroke
				(width 0.15)
				(type solid)
			)
			(layer "F.Fab")
		)
		(fp_line
			(start -0.5 -1)
			(end -0.5 1.249)
			(stroke
				(width 0.15)
				(type solid)
			)
			(layer "F.Fab")
		)
		(fp_line
			(start -0.5 1.249)
			(end 0.498 1.249)
			(stroke
				(width 0.15)
				(type solid)
			)
			(layer "F.Fab")
		)
		(fp_text user "${REFERENCE}"
			(at -0.802 4.498 90)
			(layer "F.Fab")
			(hide yes)
			(effects
				(font
					(size 0.7 0.7)
					(thickness 0.15)
				)
				(justify left bottom)
			)
		)
		(fp_text user "License: Apache-2.0"
			(at -0.802 6.9 90)
			(layer "F.Fab")
			(hide yes)
			(effects
				(font
					(size 0.7 0.7)
					(thickness 0.15)
				)
				(justify left bottom)
			)
		)
		(fp_text user "Author: Antmicro"
			(at -0.802 5.7 90)
			(layer "F.Fab")
			(hide yes)
			(effects
				(font
					(size 0.7 0.7)
					(thickness 0.15)
				)
				(justify left bottom)
			)
		)
		(pad "1" smd roundrect
			(at -0.387 -1)
			(size 0.25 0.55)
			(layers "F.Cu" "F.Paste" "F.Mask")
			(roundrect_rratio 0.25)
			(net 525 "/HDMI/HDMI_D1_CONN_N")
			(pintype "passive")
		)
		(pad "2" smd roundrect
			(at -0.387 -0.5)
			(size 0.25 0.55)
			(layers "F.Cu" "F.Paste" "F.Mask")
			(roundrect_rratio 0.25)
			(net 526 "/HDMI/HDMI_D1_CONN_P")
			(pintype "passive")
		)
		(pad "3" smd roundrect
			(at -0.387 0)
			(size 0.4 0.55)
			(layers "F.Cu" "F.Paste" "F.Mask")
			(roundrect_rratio 0.25)
			(net 1 "GND")
			(pintype "power_in")
		)
		(pad "4" smd roundrect
			(at -0.387 0.498)
			(size 0.25 0.55)
			(layers "F.Cu" "F.Paste" "F.Mask")
			(roundrect_rratio 0.25)
			(net 527 "/HDMI/HDMI_D2_CONN_N")
			(pintype "passive")
		)
		(pad "5" smd roundrect
			(at -0.387 0.998)
			(size 0.25 0.55)
			(layers "F.Cu" "F.Paste" "F.Mask")
			(roundrect_rratio 0.25)
			(net 528 "/HDMI/HDMI_D2_CONN_P")
			(pintype "passive")
		)
		(pad "6" smd roundrect
			(at 0.385 0.998)
			(size 0.25 0.55)
			(layers "F.Cu" "F.Paste" "F.Mask")
			(roundrect_rratio 0.25)
			(net 528 "/HDMI/HDMI_D2_CONN_P")
			(pintype "passive")
		)
		(pad "7" smd roundrect
			(at 0.385 0.498)
			(size 0.25 0.55)
			(layers "F.Cu" "F.Paste" "F.Mask")
			(roundrect_rratio 0.25)
			(net 527 "/HDMI/HDMI_D2_CONN_N")
			(pintype "passive")
		)
		(pad "8" smd roundrect
			(at 0.385 0)
			(size 0.4 0.55)
			(layers "F.Cu" "F.Paste" "F.Mask")
			(roundrect_rratio 0.25)
			(net 1 "GND")
			(pintype "passive")
		)
		(pad "9" smd roundrect
			(at 0.385 -0.5)
			(size 0.25 0.55)
			(layers "F.Cu" "F.Paste" "F.Mask")
			(roundrect_rratio 0.25)
			(net 526 "/HDMI/HDMI_D1_CONN_P")
			(pintype "passive")
		)
		(pad "10" smd roundrect
			(at 0.385 -1)
			(size 0.25 0.55)
			(layers "F.Cu" "F.Paste" "F.Mask")
			(roundrect_rratio 0.25)
			(net 525 "/HDMI/HDMI_D1_CONN_N")
			(pintype "passive")
		)
	)
	(footprint "antmicro-footprints:R_0402_1005Metric"
		(layer "F.Cu")
		(at 62.32 101.52)
		(descr "Resistor SMD 0402")
		(tags "resistor SMD 0402")
		(property "Reference" "R159"
			(at 2.93 3.48 0)
			(layer "F.SilkS")
			(effects
				(font
					(size 0.7 0.7)
					(thickness 0.15)
				)
				(justify left bottom)
			)
		)
		(property "Value" "R_499k_0402"
			(at -1.011843 1.772047 0)
			(layer "F.Fab")
			(effects
				(font
					(size 0.7 0.7)
					(thickness 0.15)
				)
				(justify left bottom)
			)
		)
		(property "Footprint" "antmicro-footprints:R_0402_1005Metric"
			(at 0 0 0)
			(layer "F.Fab")
			(hide yes)
			(effects
				(font
					(size 1.27 1.27)
					(thickness 0.15)
				)
			)
		)
		(property "Datasheet" "https://www.mouser.com/datasheet/2/54/cr-1858361.pdf"
			(at 0 0 0)
			(layer "F.Fab")
			(hide yes)
			(effects
				(font
					(size 1.27 1.27)
					(thickness 0.15)
				)
			)
		)
		(property "Author" "Antmicro"
			(at 0 0 0)
			(layer "F.Fab")
			(hide yes)
			(effects
				(font
					(size 1 1)
					(thickness 0.15)
				)
			)
		)
		(property "License" "Apache-2.0"
			(at 0 0 0)
			(layer "F.Fab")
			(hide yes)
			(effects
				(font
					(size 1 1)
					(thickness 0.15)
				)
			)
		)
		(property "MPN" "CR0402-FX-4993GLF"
			(at 0 0 0)
			(layer "F.Fab")
			(hide yes)
			(effects
				(font
					(size 1 1)
					(thickness 0.15)
				)
			)
		)
		(property "Manufacturer" "Bourns"
			(at 0 0 0)
			(layer "F.Fab")
			(hide yes)
			(effects
				(font
					(size 1 1)
					(thickness 0.15)
				)
			)
		)
		(property "Tolerance" "1%"
			(at 0 0 0)
			(layer "F.Fab")
			(hide yes)
			(effects
				(font
					(size 1 1)
					(thickness 0.15)
				)
			)
		)
		(property "Val" "499k"
			(at 0 0 0)
			(layer "F.Fab")
			(hide yes)
			(effects
				(font
					(size 1 1)
					(thickness 0.15)
				)
			)
		)
		(sheetname "Supply")
		(sheetfile "supply.kicad_sch")
		(attr smd exclude_from_pos_files exclude_from_bom dnp)
		(fp_rect
			(start -0.925 -0.47)
			(end 0.925 0.47)
			(stroke
				(width 0.05)
				(type default)
			)
			(fill none)
			(layer "F.CrtYd")
		)
		(fp_rect
			(start -0.5 -0.25)
			(end 0.5 0.25)
			(stroke
				(width 0.15)
				(type solid)
			)
			(fill none)
			(layer "F.Fab")
		)
		(fp_text user "License: Apache-2.0"
			(at -0.95 5.169 0)
			(layer "F.Fab")
			(hide yes)
			(effects
				(font
					(size 0.7 0.7)
					(thickness 0.15)
				)
				(justify left bottom)
			)
		)
		(fp_text user "${REFERENCE}"
			(at -0.95 3.168 0)
			(layer "F.Fab")
			(hide yes)
			(effects
				(font
					(size 0.7 0.7)
					(thickness 0.15)
				)
				(justify left bottom)
			)
		)
		(fp_text user "Author: Antmicro"
			(at -0.95 4.169 0)
			(layer "F.Fab")
			(hide yes)
			(effects
				(font
					(size 0.7 0.7)
					(thickness 0.15)
				)
				(justify left bottom)
			)
		)
		(pad "1" smd roundrect
			(at -0.48 0)
			(size 0.59 0.64)
			(layers "F.Cu" "F.Paste" "F.Mask")
			(roundrect_rratio 0.25)
			(net 764 "/Supply/5V_MODE1")
			(pintype "passive")
		)
		(pad "2" smd roundrect
			(at 0.48 0)
			(size 0.59 0.64)
			(layers "F.Cu" "F.Paste" "F.Mask")
			(roundrect_rratio 0.25)
			(net 759 "/Supply/5V_VDD")
			(pintype "passive")
		)
	)
	(footprint "antmicro-footprints:R_0402_1005Metric"
		(layer "F.Cu")
		(at 65.05 113.1 -90)
		(descr "Resistor SMD 0402")
		(tags "resistor SMD 0402")
		(property "Reference" "R158"
			(at 1.2 -1.3 -90)
			(layer "F.SilkS")
			(effects
				(font
					(size 0.7 0.7)
					(thickness 0.15)
				)
				(justify left bottom)
			)
		)
		(property "Value" "R_0R_0402"
			(at 0 1.4 -90)
			(layer "F.Fab")
			(effects
				(font
					(size 0.7 0.7)
					(thickness 0.15)
				)
				(justify left bottom)
			)
		)
		(property "Footprint" "antmicro-footprints:R_0402_1005Metric"
			(at 0 0 -90)
			(layer "F.Fab")
			(hide yes)
			(effects
				(font
					(size 1.27 1.27)
					(thickness 0.15)
				)
			)
		)
		(property "Datasheet" "https://industrial.panasonic.com/cdbs/www-data/pdf/RDA0000/AOA0000C301.pdf"
			(at 0 0 -90)
			(layer "F.Fab")
			(hide yes)
			(effects
				(font
					(size 1.27 1.27)
					(thickness 0.15)
				)
			)
		)
		(property "Author" "Antmicro"
			(at -48.05 178.15 0)
			(layer "F.Fab")
			(hide yes)
			(effects
				(font
					(size 1 1)
					(thickness 0.15)
				)
			)
		)
		(property "Current" "1A"
			(at -48.05 178.15 0)
			(layer "F.Fab")
			(hide yes)
			(effects
				(font
					(size 1 1)
					(thickness 0.15)
				)
			)
		)
		(property "License" "Apache-2.0"
			(at -48.05 178.15 0)
			(layer "F.Fab")
			(hide yes)
			(effects
				(font
					(size 1 1)
					(thickness 0.15)
				)
			)
		)
		(property "MPN" "ERJ2GE0R00X"
			(at -48.05 178.15 0)
			(layer "F.Fab")
			(hide yes)
			(effects
				(font
					(size 1 1)
					(thickness 0.15)
				)
			)
		)
		(property "Manufacturer" "Panasonic"
			(at -48.05 178.15 0)
			(layer "F.Fab")
			(hide yes)
			(effects
				(font
					(size 1 1)
					(thickness 0.15)
				)
			)
		)
		(property "Tolerance" ""
			(at -48.05 178.15 0)
			(layer "F.Fab")
			(hide yes)
			(effects
				(font
					(size 1 1)
					(thickness 0.15)
				)
			)
		)
		(property "Val" "0R"
			(at -48.05 178.15 0)
			(layer "F.Fab")
			(hide yes)
			(effects
				(font
					(size 1 1)
					(thickness 0.15)
				)
			)
		)
		(sheetname "USB Debug, DP")
		(sheetfile "usb.kicad_sch")
		(attr smd exclude_from_pos_files exclude_from_bom dnp)
		(fp_rect
			(start -0.925 -0.47)
			(end 0.925 0.47)
			(stroke
				(width 0.05)
				(type default)
			)
			(fill none)
			(layer "F.CrtYd")
		)
		(fp_rect
			(start -0.5 -0.25)
			(end 0.5 0.25)
			(stroke
				(width 0.15)
				(type solid)
			)
			(fill none)
			(layer "F.Fab")
		)
		(fp_text user "Author: Antmicro"
			(at -0.95 4.169 -90)
			(layer "F.Fab")
			(hide yes)
			(effects
				(font
					(size 0.7 0.7)
					(thickness 0.15)
				)
				(justify left bottom)
			)
		)
		(fp_text user "License: Apache-2.0"
			(at -0.95 5.169 -90)
			(layer "F.Fab")
			(hide yes)
			(effects
				(font
					(size 0.7 0.7)
					(thickness 0.15)
				)
				(justify left bottom)
			)
		)
		(fp_text user "${REFERENCE}"
			(at -0.95 3.168 -90)
			(layer "F.Fab")
			(hide yes)
			(effects
				(font
					(size 0.7 0.7)
					(thickness 0.15)
				)
				(justify left bottom)
			)
		)
		(pad "1" smd roundrect
			(at -0.48 0 270)
			(size 0.59 0.64)
			(layers "F.Cu" "F.Paste" "F.Mask")
			(roundrect_rratio 0.25)
			(net 553 "/USB Debug, DP/USBC0_5V_PEN")
			(pintype "passive")
		)
		(pad "2" smd roundrect
			(at 0.48 0 270)
			(size 0.59 0.64)
			(layers "F.Cu" "F.Paste" "F.Mask")
			(roundrect_rratio 0.25)
			(net 99 "+5V")
			(pintype "passive")
		)
	)
	(footprint "antmicro-footprints:TP_SMD_0.75mm"
		(layer "F.Cu")
		(at 92.1 118.6 90)
		(property "Reference" "TP58"
			(at 0.2 0.35 90)
			(layer "F.SilkS")
			(effects
				(font
					(size 0.7 0.7)
					(thickness 0.15)
				)
				(justify left bottom)
			)
		)
		(property "Value" "TP_0.75mm_SMD"
			(at 0 1.2 90)
			(layer "F.Fab")
			(effects
				(font
					(size 0.7 0.7)
					(thickness 0.15)
				)
				(justify left bottom)
			)
		)
		(property "Footprint" "antmicro-footprints:TP_SMD_0.75mm"
			(at 0 0 90)
			(layer "F.Fab")
			(hide yes)
			(effects
				(font
					(size 1.27 1.27)
					(thickness 0.15)
				)
			)
		)
		(property "Author" "Antmicro"
			(at 210.7 26.5 0)
			(layer "F.Fab")
			(hide yes)
			(effects
				(font
					(size 1 1)
					(thickness 0.15)
				)
			)
		)
		(property "License" "Apache-2.0"
			(at 210.7 26.5 0)
			(layer "F.Fab")
			(hide yes)
			(effects
				(font
					(size 1 1)
					(thickness 0.15)
				)
			)
		)
		(property "MPN" ""
			(at 210.7 26.5 0)
			(layer "F.Fab")
			(hide yes)
			(effects
				(font
					(size 1 1)
					(thickness 0.15)
				)
			)
		)
		(property "Manufacturer" ""
			(at 210.7 26.5 0)
			(layer "F.Fab")
			(hide yes)
			(effects
				(font
					(size 1 1)
					(thickness 0.15)
				)
			)
		)
		(sheetname "HDMI")
		(sheetfile "hdmi.kicad_sch")
		(attr exclude_from_pos_files exclude_from_bom)
		(fp_circle
			(center 0 0)
			(end 0.475 0)
			(stroke
				(width 0.05)
				(type default)
			)
			(fill none)
			(layer "F.CrtYd")
		)
		(fp_text user "Author: Antmicro"
			(at -0.4 3.901 90)
			(layer "F.Fab")
			(hide yes)
			(effects
				(font
					(size 0.7 0.7)
					(thickness 0.15)
				)
				(justify left bottom)
			)
		)
		(fp_text user "License: Apache-2.0"
			(at -0.4 5.101 90)
			(layer "F.Fab")
			(hide yes)
			(effects
				(font
					(size 0.7 0.7)
					(thickness 0.15)
				)
				(justify left bottom)
			)
		)
		(fp_text user "${REFERENCE}"
			(at -0.4 2.7 90)
			(layer "F.Fab")
			(hide yes)
			(effects
				(font
					(size 0.7 0.7)
					(thickness 0.15)
				)
				(justify left bottom)
			)
		)
		(pad "1" smd circle
			(at 0 0 90)
			(size 0.75 0.75)
			(layers "F.Cu" "F.Mask")
			(net 520 "/HDMI/HDMI_CEC_5V")
			(pinfunction "1")
			(pintype "passive")
		)
	)
	(footprint "antmicro-footprints:R_0402_1005Metric"
		(layer "F.Cu")
		(at 92.59 105.41 45)
		(descr "Resistor SMD 0402")
		(tags "resistor SMD 0402")
		(property "Reference" "R209"
			(at -1.753625 1.484924 45)
			(layer "F.SilkS")
			(effects
				(font
					(size 0.7 0.7)
					(thickness 0.15)
				)
				(justify left bottom)
			)
		)
		(property "Value" "R_499R_0402"
			(at -1.011843 1.772046 45)
			(layer "F.Fab")
			(effects
				(font
					(size 0.7 0.7)
					(thickness 0.15)
				)
				(justify left bottom)
			)
		)
		(property "Footprint" "antmicro-footprints:R_0402_1005Metric"
			(at 0 0 45)
			(layer "F.Fab")
			(hide yes)
			(effects
				(font
					(size 1.27 1.27)
					(thickness 0.15)
				)
			)
		)
		(property "Datasheet" "https://www.mouser.com/datasheet/2/54/cr-1858361.pdf"
			(at 0 0 45)
			(layer "F.Fab")
			(hide yes)
			(effects
				(font
					(size 1.27 1.27)
					(thickness 0.15)
				)
			)
		)
		(property "Author" "Antmicro"
			(at 101.655109 -34.597142 0)
			(layer "F.Fab")
			(hide yes)
			(effects
				(font
					(size 1 1)
					(thickness 0.15)
				)
			)
		)
		(property "License" "Apache-2.0"
			(at 101.655109 -34.597142 0)
			(layer "F.Fab")
			(hide yes)
			(effects
				(font
					(size 1 1)
					(thickness 0.15)
				)
			)
		)
		(property "MPN" "CR0402-FX-4990GLF"
			(at 101.655109 -34.597142 0)
			(layer "F.Fab")
			(hide yes)
			(effects
				(font
					(size 1 1)
					(thickness 0.15)
				)
			)
		)
		(property "Manufacturer" "Bourns"
			(at 101.655109 -34.597142 0)
			(layer "F.Fab")
			(hide yes)
			(effects
				(font
					(size 1 1)
					(thickness 0.15)
				)
			)
		)
		(property "Tolerance" "1%"
			(at 101.655109 -34.597142 0)
			(layer "F.Fab")
			(hide yes)
			(effects
				(font
					(size 1 1)
					(thickness 0.15)
				)
			)
		)
		(property "Val" "499R"
			(at 101.655109 -34.597142 0)
			(layer "F.Fab")
			(hide yes)
			(effects
				(font
					(size 1 1)
					(thickness 0.15)
				)
			)
		)
		(sheetname "HDMI")
		(sheetfile "hdmi.kicad_sch")
		(attr smd)
		(fp_poly
			(pts
				(xy -0.925 -0.47) (xy 0.925 -0.47) (xy 0.925 0.47) (xy -0.925 0.47)
			)
			(stroke
				(width 0.05)
				(type default)
			)
			(fill none)
			(layer "F.CrtYd")
		)
		(fp_poly
			(pts
				(xy -0.5 -0.25) (xy 0.5 -0.25) (xy 0.5 0.25) (xy -0.5 0.25)
			)
			(stroke
				(width 0.15)
				(type solid)
			)
			(fill none)
			(layer "F.Fab")
		)
		(fp_text user "License: Apache-2.0"
			(at -0.949999 5.169 45)
			(layer "F.Fab")
			(hide yes)
			(effects
				(font
					(size 0.7 0.7)
					(thickness 0.15)
				)
				(justify left bottom)
			)
		)
		(fp_text user "${REFERENCE}"
			(at -0.95 3.168 45)
			(layer "F.Fab")
			(hide yes)
			(effects
				(font
					(size 0.7 0.7)
					(thickness 0.15)
				)
				(justify left bottom)
			)
		)
		(fp_text user "Author: Antmicro"
			(at -0.95 4.169 45)
			(layer "F.Fab")
			(hide yes)
			(effects
				(font
					(size 0.7 0.7)
					(thickness 0.15)
				)
				(justify left bottom)
			)
		)
		(pad "1" smd roundrect
			(at -0.48 0 45)
			(size 0.59 0.64)
			(layers "F.Cu" "F.Paste" "F.Mask")
			(roundrect_rratio 0.25)
			(net 623 "Net-(Q2-D)")
			(pintype "passive")
		)
		(pad "2" smd roundrect
			(at 0.48 0 45)
			(size 0.59 0.64)
			(layers "F.Cu" "F.Paste" "F.Mask")
			(roundrect_rratio 0.25)
			(net 486 "/HDMI/HDMI_D2_N")
			(pintype "passive")
		)
	)
)
